FILE_TYPE = MULTI_PHYS_TABLE;

PART 'SW_PUSHBUTTON4P_24'

{========================================================================================}
:VALUE                   | PART_TYPE | MATERIAL | PART_NUMBER            = STANDARD | LIFECYCLE      | PART_NUMBER            | JEDEC_TYPE           | DESCRIPTION                                | MANUFTR | MANUF_PN           | RD_CMPLS_LVL | CMPLS_LVL | CLASS | DIP_SMD | FROM_PJ        | DATA                         | FP_ECN | EE_CHECK_LIST | PSL | PREFERENCE | CREATOR | CREATEDAY  | STATUS ;
{========================================================================================}
 'SW4S_TL3304AF160QJ'    | 'SMLF'    | 'MECH'   | 'DHPTL330416'(!)       = ''       | ''             | 'DHPTL330416'          |'SW4S_TL3304AF160QJ'| 'SWITCH SMD PUSH TL3304AF160QJ'            | 'ESH'   | 'TL3304AF160QJ'    | 'EU(V1)'     | 'SEA'     | 'IO'  | ''      | 'S2U-MING-LI'  | 'ESH_TL3304AF160QJ.pdf'      | ''     | ''            | ''  | ''         | ''      | '20120811' | ''    
 'SW4S_TL3304AF160QJ'    | 'SMLF'    | 'EMPTY'  | 'DHPTL330416'(!)       = ''       | ''             | 'DHPTL330416'          |'SW4S_TL3304AF160QJ'| 'SWITCH SMD PUSH TL3304AF160QJ'            | 'ESH'   | 'TL3304AF160QJ'    | 'EU(V1)'     | 'SEA'     | 'IO'  | ''      | 'S2U-MING-LI'  | 'ESH_TL3304AF160QJ.pdf'      | ''     | ''            | ''  | ''         | ''      | '20120811' | ''    
 'SW4S_DTSM-61N'         | 'SMLF'    | 'MECH'   | 'DHP00061N00'(!)       = ''       | ''             | 'DHP00061N00'          |'SW4S_DTSM-61N'| 'SWITCH PUSH BUTTON(H4.3)DTSM-61N-S-V-T/R' | 'DIP'   | 'DTSM-61N-S-V-T/R' | 'EP'         | 'EP'      | 'IO'  | ''      | 'S4L-TREE'     | 'DIP_RD5P6M-V.pdf'           | ''     | ''            | ''  | ''         | ''      | '20130419' | ''    
 'SW4S_DTSM-61N'         | 'SMLF'    | 'EMPTY'  | 'DHP00061N00'(!)       = ''       | ''             | 'DHP00061N00'          |'SW4S_DTSM-61N'| 'SWITCH PUSH BUTTON(H4.3)DTSM-61N-S-V-T/R' | 'DIP'   | 'DTSM-61N-S-V-T/R' | 'EP'         | 'EP'      | 'IO'  | ''      | 'S4L-TREE'     | 'DIP_RD5P6M-V.pdf'           | ''     | ''            | ''  | ''         | ''      | '20130419' | ''    
 'SW4S_DTSM-65K-Q-T/R'   | 'SMLF'    | 'MECH'   | 'DHPDTSM6500'(!)       = ''       | ''             | 'DHPDTSM6500'          |'SW4S_DTSM-65N'| 'SWITCH SMD TACT 4P(DTSM-65K-Q-T/R)'       | 'DIP'   | 'DTSM-65K-Q-T/R'   | 'EU(V1)'     | ''        | 'IO'  | ''      | 'S2P-SEAN'     | 'DIP_DTSM-65K-Q-TR_REVA.pdf' | ''     | ''            | ''  | ''         | ''      | '20140521' | ''    
 'SW4S_DTSM-65K-Q-T/R'   | 'SMLF'    | 'EMPTY'  | 'DHPDTSM6500'(!)       = ''       | ''             | 'DHPDTSM6500'          |'SW4S_DTSM-65N'| 'SWITCH SMD TACT 4P(DTSM-65K-Q-T/R)'       | 'DIP'   | 'DTSM-65K-Q-T/R'   | 'EU(V1)'     | ''        | 'IO'  | ''      | 'S2P-SEAN'     | 'DIP_DTSM-65K-Q-TR_REVA.pdf' | ''     | ''            | ''  | ''         | ''      | '20140521' | ''    
 'SW4S_DTSM-65N-S-Q-TR'  | 'SMLF'    | 'MECH'   | 'DHP00065N03'(!)       = ''       | ''             | 'DHP00065N03'          |'SW_DTSM-62N-S-V-TR'| 'SWITCH PUSH BUTTON DTSM-65N-S-Q-T/R H9.5' | 'DIP'   | 'DTSM-65N-S-Q-T/R' | 'EP(V1)'     | ''        | 'IO'  | ''      | 'T2R-GAVEN'    | 'DIP_DTSM-65N-S-Q-TR.pdf'    | ''     | ''            | ''  | ''         | ''      | '20140711' | ''    
 'SW4S_DTSM-65N-S-Q-TR'  | 'SMLF'    | 'EMPTY'  | 'DHP00065N03'(!)       = ''       | ''             | 'DHP00065N03'          |'SW_DTSM-62N-S-V-TR'| 'SWITCH PUSH BUTTON DTSM-65N-S-Q-T/R H9.5' | 'DIP'   | 'DTSM-65N-S-Q-T/R' | 'EP(V1)'     | ''        | 'IO'  | ''      | 'T2R-GAVEN'    | 'DIP_DTSM-65N-S-Q-TR.pdf'    | ''     | ''            | ''  | ''         | ''      | '20140711' | ''    
 'SW4P_DTS-65R-V(766)'   | 'THLF'    | 'MECH'   | 'DHP00065R01'(!)       = ''       | ''             | 'DHP00065R01'          |'SW_DTS-65K-V'| 'SWITCH TACT(DTS-65R-V(766))'              | 'DIP'   | 'DTS-65R-V(766)'   | 'EU(V1)'     | ''        | 'IO'  | 'DIP'   | 'S6A-MEALY'    | 'DIP_DTS-65R-V766_REVA.pdf'  | ''     | ''            | ''  | ''         | ''      | '20141127' | ''    
 'SW4P_DTS-65R-V(766)'   | 'THLF'    | 'EMPTY'  | 'DHP00065R01'(!)       = ''       | ''             | 'DHP00065R01'          |'SW_DTS-65K-V'| 'SWITCH TACT(DTS-65R-V(766))'              | 'DIP'   | 'DTS-65R-V(766)'   | 'EU(V1)'     | ''        | 'IO'  | 'DIP'   | 'S6A-MEALY'    | 'DIP_DTS-65R-V766_REVA.pdf'  | ''     | ''            | ''  | ''         | ''      | '20141127' | ''    
 'SW4P_DTS-65K-V(766)'   | 'THLF'    | 'MECH'   | 'DHP00065K02'(!)       = ''       | ''             | 'DHP00065K02'          |'SW_DTS-65K-V'| 'SWITCH TACT(DTS-65K-V(766))'              | 'DIP'   | 'DTS-65K-V(766)'   | 'EU(V1)'     | ''        | 'IO'  | 'DIP'   | 'S6A-MEALY'    | 'DIP_DTS-65K-V766_REVA.pdf'  | ''     | ''            | ''  | ''         | ''      | '20141210' | ''    
 'SW4P_DTS-65K-V(766)'   | 'THLF'    | 'EMPTY'  | 'DHP00065K02'(!)       = ''       | ''             | 'DHP00065K02'          |'SW_DTS-65K-V'| 'SWITCH TACT(DTS-65K-V(766))'              | 'DIP'   | 'DTS-65K-V(766)'   | 'EU(V1)'     | ''        | 'IO'  | 'DIP'   | 'S6A-MEALY'    | 'DIP_DTS-65K-V766_REVA.pdf'  | ''     | ''            | ''  | ''         | ''      | '20141210' | ''    
 'SW4S_TBFF13KQR'        | 'SMLF'    | 'MECH'   | 'DHP013KQR00'(!)       = ''       | ''             | 'DHP013KQR00'          |'SW4S_TBFF13KQR'| 'SWITCH TACT SMD 4P(TBFF13KQR)'            | 'DIP'   | 'TBFF13KQR'        | 'EU(V1)'     | ''        | 'IO'  | ''      | 'S5B-SEAN'     | 'DIP_TBFF13KQR.pdf'          | ''     | ''            | ''  | ''         | ''      | '20151104' | ''    
 'SW4S_TBFF13KQR'        | 'SMLF'    | 'EMPTY'  | 'DHP013KQR00'(!)       = ''       | ''             | 'DHP013KQR00'          |'SW4S_TBFF13KQR'| 'SWITCH TACT SMD 4P(TBFF13KQR)'            | 'DIP'   | 'TBFF13KQR'        | 'EU(V1)'     | ''        | 'IO'  | ''      | 'S5B-SEAN'     | 'DIP_TBFF13KQR.pdf'          | ''     | ''            | ''  | ''         | ''      | '20151104' | ''    
 'SW4P_DTS-61K-Q'        | 'THLF'    | 'MECH'   | 'DHPDTS61K00'(!)       = ''       | ''             | 'DHPDTS61K00'          |'SW4P_DTS-61'| 'SWITCH TACT(DTS-61K-Q,50MA,12V)'          | 'DIP'   | 'DTS-61K-Q'        | 'EU(V1)'     | ''        | 'IO'  | ''      | 'S1F-STANLEY'  | 'DIP_RD5P6-Q.pdf'            | ''     | ''            | ''  | ''         | ''      | '20180817' | ''    
 'SW4P_DTS-61K-Q'        | 'THLF'    | 'EMPTY'  | 'DHPDTS61K00'(!)       = ''       | ''             | 'DHPDTS61K00'          |'SW4P_DTS-61'| 'SWITCH TACT(DTS-61K-Q,50MA,12V)'          | 'DIP'   | 'DTS-61K-Q'        | 'EU(V1)'     | ''        | 'IO'  | ''      | 'S1F-STANLEY'  | 'DIP_RD5P6-Q.pdf'            | ''     | ''            | ''  | ''         | ''      | '20180817' | ''    
 'SW4P_DTS-63N-Q'        | 'THLF'    | 'MECH'   | 'TMP_XG1_ROSSI_1222_1'(!) = ''       | ''             | 'TMP_XG1_ROSSI_1222_1' |'SW4P_DTS-63N-Q'| 'SWITCH DIP TACT(DTS-63N-Q)'               | 'DIP'   | 'DTS-63N-Q'        | ''           | ''        | 'IO'  | ''      | 'XG1-ROSSI'    | 'DIP_DTS-63N-Q.pdf'          | ''     | ''            | ''  | ''         | ''      | '20181222' | ''    
 'SW4P_DTS-63N-Q'        | 'THLF'    | 'EMPTY'  | 'TMP_XG1_ROSSI_1222_1'(!) = ''       | ''             | 'TMP_XG1_ROSSI_1222_1' |'SW4P_DTS-63N-Q'| 'SWITCH DIP TACT(DTS-63N-Q)'               | 'DIP'   | 'DTS-63N-Q'        | ''           | ''        | 'IO'  | ''      | 'XG1-ROSSI'    | 'DIP_DTS-63N-Q.pdf'          | ''     | ''            | ''  | ''         | ''      | '20181222' | ''    
 'SW4S_DTSM-61N-S-Q-T/R' | 'SMLF'    | 'MECH'   | 'DHP00061N15'(!)       = ''       | ''             | 'DHP00061N15'          |'SW4S_DTSM-61N'| 'SWITCH TACT SMD DTSM-61N-S-Q-T/R'         | 'DIP'   | 'DTSM-61N-S-Q-T/R' | 'EP(V1)'     | 'EP(V1)'  | 'IO'  | ''      | 'F0C-BOSUN'    | 'DIP_DTSM-61N-S-Q-TR.pdf'    | ''     | ''            | ''  | ''         | ''      | '20200215' | ''    
 'SW4S_DTSM-61N-S-Q-T/R' | 'SMLF'    | 'EMPTY'  | 'DHP00061N15'(!)       = ''       | ''             | 'DHP00061N15'          |'SW4S_DTSM-61N'| 'SWITCH TACT SMD DTSM-61N-S-Q-T/R'         | 'DIP'   | 'DTSM-61N-S-Q-T/R' | 'EP(V1)'     | 'EP(V1)'  | 'IO'  | ''      | 'F0C-BOSUN'    | 'DIP_DTSM-61N-S-Q-TR.pdf'    | ''     | ''            | ''  | ''         | ''      | '20200215' | ''    
 'SW4S_DTSM-65R-Q-T/R'   | 'SMLF'    | 'MECH'   | 'DHP00006505'(!)       = ''       | ''               | 'DHP00006505'          |'SW4S_DTSM-65N'| 'SWITCH SMD TACT(DTSM-65R-Q-T/R)'          | 'DIP'   | 'DTSM-65R-Q-T/R'   | 'EP(V1)'     | 'EP(V1)'  | 'IO'  | ''      | 'S2VD-VINCENT' | 'DIP_DTSM-65R-Q-TR.pdf'      | ''     | ''            | ''  | ''         | ''      | '20201027' | ''    
 'SW4S_DTSM-65R-Q-T/R'   | 'SMLF'    | 'EMPTY'  | 'DHP00006505'(!)       = ''       | ''               | 'DHP00006505'          |'SW4S_DTSM-65N'| 'SWITCH SMD TACT(DTSM-65R-Q-T/R)'          | 'DIP'   | 'DTSM-65R-Q-T/R'   | 'EP(V1)'     | 'EP(V1)'  | 'IO'  | ''      | 'S2VD-VINCENT' | 'DIP_DTSM-65R-Q-TR.pdf'      | ''     | ''            | ''  | ''         | ''      | '20201027' | ''    

END_PART

END.

